# S9S_MB_2U (Grand Teton) — schematic netlist excerpt (pin names and nets, part order shuffled) for the footprints in the layout excerpt that follows; sources: Cadence DE-HDL packaged netlist, KiCad conversion of 03242023_DA0F0TMBIJ0_F0T_Motherboard_J_brd_V01_OCP.brd

C1017  Q_CAP  22UF 4V 20% X6S  pkg C0402  page 74 : A = PVCCIN_CPU0 ; B = GND
PR5484  Q_RES  30.1K 1% EMPTY  pkg 0402LF  page 156 : A = P12V_OCP_CB_1 ; B = GND

(kicad_pcb
	(version 20260206)
	(generator "pcbnew")
	(generator_version "10.0")
	(general
		(thickness 1.6)
		(legacy_teardrops no)
	)
	(paper "A4")
	(title_block
		(title "03242023_DA0F0TMBIJ0_F0T_Motherboard_J_brd_V01_OCP.brd")
		(comment 1 "Grand Teton / footprints 335-336 of 6105")
	)
	(layers
		(0 "F.Cu" signal "TOP")
		(4 "In1.Cu" signal "GND")
		(6 "In2.Cu" signal "IN1")
		(8 "In3.Cu" signal "GND1")
		(10 "In4.Cu" signal "IN2")
		(12 "In5.Cu" signal "GND2")
		(14 "In6.Cu" signal "IN3")
		(16 "In7.Cu" signal "GND3")
		(18 "In8.Cu" signal "VCC")
		(20 "In9.Cu" signal "VCC1")
		(22 "In10.Cu" signal "GND4")
		(24 "In11.Cu" signal "IN4")
		(26 "In12.Cu" signal "GND5")
		(28 "In13.Cu" signal "IN5")
		(30 "In14.Cu" signal "GND6")
		(32 "In15.Cu" signal "IN6")
		(34 "In16.Cu" signal "GND7")
		(2 "B.Cu" signal "BOTTOM")
		(9 "F.Adhes" user "F.Adhesive")
		(11 "B.Adhes" user "B.Adhesive")
		(13 "F.Paste" user "Package Geometry/Pastemask Top")
		(15 "B.Paste" user "Package Geometry/Pastemask Bottom")
		(5 "F.SilkS" user "Ref Des/Silkscreen Top")
		(7 "B.SilkS" user "Ref Des/Silkscreen Bottom")
		(1 "F.Mask" user "Board Geometry/Soldermask Top")
		(3 "B.Mask" user "Board Geometry/Soldermask Bottom")
		(17 "Dwgs.User" user "User.Drawings")
		(19 "Cmts.User" user "User.Comments")
		(21 "Eco1.User" user "User.Eco1")
		(23 "Eco2.User" user "User.Eco2")
		(25 "Edge.Cuts" user "Board Geometry/Outline")
		(27 "Margin" user)
		(31 "F.CrtYd" user "Package Geometry/Place Bound Top")
		(29 "B.CrtYd" user "Package Geometry/Place Bound Bottom")
		(35 "F.Fab" user "Ref Des/Assembly Top")
		(33 "B.Fab" user "Ref Des/Assembly Bottom")
	)
	(footprint ""
		(layer "F.Cu")
		(at 447.687192 -21.236178 180)
		(property "Reference" "PR5484"
			(at 0 0 180)
			(layer "F.SilkS")
			(hide yes)
			(effects
				(font
					(size 1.27 1.27)
				)
			)
		)
		(property "Value" ""
			(at 0 0 180)
			(layer "F.Fab")
			(effects
				(font
					(size 1.27 1.27)
				)
			)
		)
		(duplicate_pad_numbers_are_jumpers no)
		(fp_line
			(start 0.7874 0.4064)
			(end -0.7874 0.4064)
			(stroke
				(width 0.1524)
				(type default)
			)
			(layer "F.SilkS")
		)
		(fp_line
			(start 0.7874 -0.4064)
			(end 0.7874 0.4064)
			(stroke
				(width 0.1524)
				(type default)
			)
			(layer "F.SilkS")
		)
		(fp_line
			(start -0.7874 0.4064)
			(end -0.7874 -0.4064)
			(stroke
				(width 0.1524)
				(type default)
			)
			(layer "F.SilkS")
		)
		(fp_line
			(start -0.7874 -0.4064)
			(end 0.7874 -0.4064)
			(stroke
				(width 0.1524)
				(type default)
			)
			(layer "F.SilkS")
		)
		(fp_line
			(start 0.67945 0.3048)
			(end 0.120396 0.3048)
			(stroke
				(width 0.1)
				(type default)
			)
			(layer "F.Fab")
		)
		(fp_line
			(start 0.67945 -0.3048)
			(end 0.67945 0.3048)
			(stroke
				(width 0.1)
				(type default)
			)
			(layer "F.Fab")
		)
		(fp_line
			(start 0.12065 -0.2794)
			(end 0.12065 -0.3048)
			(stroke
				(width 0.1)
				(type default)
			)
			(layer "F.Fab")
		)
		(fp_line
			(start 0.12065 -0.3048)
			(end 0.67945 -0.3048)
			(stroke
				(width 0.1)
				(type default)
			)
			(layer "F.Fab")
		)
		(fp_line
			(start 0.120396 0.3048)
			(end 0.120396 0.2794)
			(stroke
				(width 0.1)
				(type default)
			)
			(layer "F.Fab")
		)
		(fp_line
			(start 0.120396 0.2794)
			(end -0.12065 0.2794)
			(stroke
				(width 0.1)
				(type default)
			)
			(layer "F.Fab")
		)
		(fp_line
			(start -0.12065 0.3048)
			(end -0.67945 0.3048)
			(stroke
				(width 0.1)
				(type default)
			)
			(layer "F.Fab")
		)
		(fp_line
			(start -0.12065 0.2794)
			(end -0.12065 0.3048)
			(stroke
				(width 0.1)
				(type default)
			)
			(layer "F.Fab")
		)
		(fp_line
			(start -0.12065 -0.2794)
			(end 0.12065 -0.2794)
			(stroke
				(width 0.1)
				(type default)
			)
			(layer "F.Fab")
		)
		(fp_line
			(start -0.12065 -0.305054)
			(end -0.12065 -0.2794)
			(stroke
				(width 0.1)
				(type default)
			)
			(layer "F.Fab")
		)
		(fp_line
			(start -0.67945 0.3048)
			(end -0.67945 -0.305054)
			(stroke
				(width 0.1)
				(type default)
			)
			(layer "F.Fab")
		)
		(fp_line
			(start -0.67945 -0.305054)
			(end -0.12065 -0.305054)
			(stroke
				(width 0.1)
				(type default)
			)
			(layer "F.Fab")
		)
		(pad "1" smd circle
			(at -0.40005 0 180)
			(size 0 0)
			(layers "F.Cu" "F.Mask" "F.Paste")
			(net "P12V_OCP_CB_1")
		)
		(pad "2" smd circle
			(at 0.40005 0 180)
			(size 0 0)
			(layers "F.Cu" "F.Mask" "F.Paste")
			(net "GND")
		)
	)
	(footprint ""
		(layer "F.Cu")
		(at 366.48263 -244.03177 90)
		(property "Reference" "C1017"
			(at 0 0 90)
			(layer "F.SilkS")
			(hide yes)
			(effects
				(font
					(size 1.27 1.27)
				)
			)
		)
		(property "Value" ""
			(at 0 0 90)
			(layer "F.Fab")
			(effects
				(font
					(size 1.27 1.27)
				)
			)
		)
		(duplicate_pad_numbers_are_jumpers no)
		(fp_line
			(start 0.7874 -0.4064)
			(end 0.7874 0.4064)
			(stroke
				(width 0.1524)
				(type default)
			)
			(layer "F.SilkS")
		)
		(fp_line
			(start -0.7874 -0.4064)
			(end 0.7874 -0.4064)
			(stroke
				(width 0.1524)
				(type default)
			)
			(layer "F.SilkS")
		)
		(fp_line
			(start 0.7874 0.4064)
			(end -0.7874 0.4064)
			(stroke
				(width 0.1524)
				(type default)
			)
			(layer "F.SilkS")
		)
		(fp_line
			(start -0.7874 0.4064)
			(end -0.7874 -0.4064)
			(stroke
				(width 0.1524)
				(type default)
			)
			(layer "F.SilkS")
		)
		(fp_line
			(start -0.12065 -0.305054)
			(end -0.12065 -0.2794)
			(stroke
				(width 0.1)
				(type default)
			)
			(layer "F.Fab")
		)
		(fp_line
			(start -0.67945 -0.305054)
			(end -0.12065 -0.305054)
			(stroke
				(width 0.1)
				(type default)
			)
			(layer "F.Fab")
		)
		(fp_line
			(start 0.67945 -0.3048)
			(end 0.67945 0.3048)
			(stroke
				(width 0.1)
				(type default)
			)
			(layer "F.Fab")
		)
		(fp_line
			(start 0.12065 -0.3048)
			(end 0.67945 -0.3048)
			(stroke
				(width 0.1)
				(type default)
			)
			(layer "F.Fab")
		)
		(fp_line
			(start 0.12065 -0.2794)
			(end 0.12065 -0.3048)
			(stroke
				(width 0.1)
				(type default)
			)
			(layer "F.Fab")
		)
		(fp_line
			(start -0.12065 -0.2794)
			(end 0.12065 -0.2794)
			(stroke
				(width 0.1)
				(type default)
			)
			(layer "F.Fab")
		)
		(fp_line
			(start 0.120396 0.2794)
			(end -0.12065 0.2794)
			(stroke
				(width 0.1)
				(type default)
			)
			(layer "F.Fab")
		)
		(fp_line
			(start -0.12065 0.2794)
			(end -0.12065 0.3048)
			(stroke
				(width 0.1)
				(type default)
			)
			(layer "F.Fab")
		)
		(fp_line
			(start 0.67945 0.3048)
			(end 0.120396 0.3048)
			(stroke
				(width 0.1)
				(type default)
			)
			(layer "F.Fab")
		)
		(fp_line
			(start 0.120396 0.3048)
			(end 0.120396 0.2794)
			(stroke
				(width 0.1)
				(type default)
			)
			(layer "F.Fab")
		)
		(fp_line
			(start -0.12065 0.3048)
			(end -0.67945 0.3048)
			(stroke
				(width 0.1)
				(type default)
			)
			(layer "F.Fab")
		)
		(fp_line
			(start -0.67945 0.3048)
			(end -0.67945 -0.305054)
			(stroke
				(width 0.1)
				(type default)
			)
			(layer "F.Fab")
		)
		(pad "1" smd circle
			(at -0.40005 0 90)
			(size 0 0)
			(layers "F.Cu" "F.Mask" "F.Paste")
			(net "PVCCIN_CPU0")
		)
		(pad "2" smd circle
			(at 0.40005 0 90)
			(size 0 0)
			(layers "F.Cu" "F.Mask" "F.Paste")
			(net "GND")
		)
	)
)
